# TIMECARD (Time Appliance Project (Time Card)) — schematic netlist excerpt (pin names and nets, part order shuffled) for the footprints in the layout excerpt that follows; sources: Cadence DE-HDL packaged netlist, KiCad conversion of R4006-B0001-02_R01.brd

C240  CAPACITOR  22UF 10V 20%  pkg SMC_0805R_H057  page 31 : \1\ = XP3R3V_FPGA ; \2\ = SG
R11  RESISTOR  120KOHM 1%  pkg SMC_0402R_H016  page 27 : \1\ = XP12R0V_IN ; \2\ = XP12R0V_A_OV

(kicad_pcb
	(version 20260206)
	(generator "pcbnew")
	(generator_version "10.0")
	(general
		(thickness 1.6)
		(legacy_teardrops no)
	)
	(paper "A4")
	(title_block
		(title "timecard-production-celestica-r4006 — R4006-B0001-02_R01.brd")
		(comment 1 "Time Appliance Project (Time Card) / footprints 129-130 of 1113")
	)
	(layers
		(0 "F.Cu" signal "TOP")
		(4 "In1.Cu" signal "L02_GND1")
		(6 "In2.Cu" signal "L03_SIG1")
		(8 "In3.Cu" signal "L04_GND2")
		(10 "In4.Cu" signal "L05_VCC1")
		(12 "In5.Cu" signal "L06_VCC2")
		(14 "In6.Cu" signal "L07_GND3")
		(16 "In7.Cu" signal "L08_SIG2")
		(18 "In8.Cu" signal "L09_GND4")
		(2 "B.Cu" signal "BOTTOM")
		(9 "F.Adhes" user "F.Adhesive")
		(11 "B.Adhes" user "B.Adhesive")
		(13 "F.Paste" user "Package Geometry/Pastemask Top")
		(15 "B.Paste" user "Package Geometry/Pastemask Bottom")
		(5 "F.SilkS" user "Ref Des/Silkscreen Top")
		(7 "B.SilkS" user "Ref Des/Silkscreen Bottom")
		(1 "F.Mask" user "Board Geometry/Soldermask Top")
		(3 "B.Mask" user "Board Geometry/Soldermask Bottom")
		(17 "Dwgs.User" user "User.Drawings")
		(19 "Cmts.User" user "User.Comments")
		(21 "Eco1.User" user "User.Eco1")
		(23 "Eco2.User" user "User.Eco2")
		(25 "Edge.Cuts" user "Board Geometry/Outline")
		(27 "Margin" user)
		(31 "F.CrtYd" user "Package Geometry/Place Bound Top")
		(29 "B.CrtYd" user "Package Geometry/Place Bound Bottom")
		(35 "F.Fab" user "Ref Des/Assembly Top")
		(33 "B.Fab" user "Ref Des/Assembly Bottom")
	)
	(footprint ""
		(layer "F.Cu")
		(at 135.6614 -100.5078)
		(property "Reference" "R11"
			(at -2.0574 -0.29083 0)
			(unlocked yes)
			(layer "F.SilkS")
			(effects
				(font
					(size 0.7874 0.5842)
					(thickness 0.1524)
				)
			)
		)
		(property "Value" "VAL*"
			(at 0.02032 2.13233 0)
			(unlocked yes)
			(layer "F.Fab")
			(hide yes)
			(effects
				(font
					(size 0.7874 0.5842)
					(thickness 0.1524)
				)
			)
		)
		(property "Device Type" "RESISTOR-G155-01203-01,120KOHMA"
			(at 0.008382 1.210564 0)
			(unlocked yes)
			(layer "F.Fab")
			(hide yes)
			(effects
				(font
					(size 0.7874 0.5842)
					(thickness 0.1524)
				)
			)
		)
		(property "User Part Number" "PARTNUM*"
			(at 0.02032 4.024884 0)
			(unlocked yes)
			(layer "Cmts.User")
			(hide yes)
			(effects
				(font
					(size 0.7874 0.5842)
					(thickness 0.1524)
				)
			)
		)
		(property "Tolerance" "TOL*"
			(at 0.044704 3.05435 0)
			(unlocked yes)
			(layer "Cmts.User")
			(hide yes)
			(effects
				(font
					(size 0.7874 0.5842)
					(thickness 0.1524)
				)
			)
		)
		(duplicate_pad_numbers_are_jumpers no)
		(fp_line
			(start -1.143 -0.5588)
			(end -1.143 0.5588)
			(stroke
				(width 0.1)
				(type default)
			)
			(layer "F.SilkS")
		)
		(fp_line
			(start -1.143 0.5588)
			(end 1.143 0.5588)
			(stroke
				(width 0.1)
				(type default)
			)
			(layer "F.SilkS")
		)
		(fp_line
			(start 1.143 -0.5588)
			(end -1.143 -0.5588)
			(stroke
				(width 0.1)
				(type default)
			)
			(layer "F.SilkS")
		)
		(fp_line
			(start 1.143 0.5588)
			(end 1.143 -0.5588)
			(stroke
				(width 0.1)
				(type default)
			)
			(layer "F.SilkS")
		)
		(fp_rect
			(start -1.143 0.5588)
			(end 1.143 -0.5588)
			(stroke
				(width 0)
				(type default)
			)
			(fill no)
			(layer "F.CrtYd")
		)
		(fp_line
			(start -0.508 -0.3048)
			(end -0.508 0.3048)
			(stroke
				(width 0.1)
				(type default)
			)
			(layer "F.Fab")
		)
		(fp_line
			(start -0.508 0.3048)
			(end 0.508 0.3048)
			(stroke
				(width 0.1)
				(type default)
			)
			(layer "F.Fab")
		)
		(fp_line
			(start 0.508 -0.3048)
			(end -0.508 -0.3048)
			(stroke
				(width 0.1)
				(type default)
			)
			(layer "F.Fab")
		)
		(fp_line
			(start 0.508 0.3048)
			(end 0.508 -0.3048)
			(stroke
				(width 0.1)
				(type default)
			)
			(layer "F.Fab")
		)
		(pad "1" smd rect
			(at -0.5334 0)
			(size 0.7112 0.6096)
			(layers "F.Cu" "F.Mask" "F.Paste")
			(net "XP12R0V_IN")
		)
		(pad "2" smd rect
			(at 0.5334 0)
			(size 0.7112 0.6096)
			(layers "F.Cu" "F.Mask" "F.Paste")
			(net "XP12R0V_A_OV")
		)
		(zone
			(layer "F.Cu")
			(hatch none 0.5)
			(connect_pads
				(clearance 0)
			)
			(min_thickness 0.25)
			(keepout
				(tracks allowed)
				(vias not_allowed)
				(pads allowed)
				(copperpour not_allowed)
				(footprints allowed)
			)
			(placement
				(enabled no)
				(sheetname "")
			)
			(fill
				(thermal_gap 0.5)
				(thermal_bridge_width 0.5)
				(island_removal_mode 0)
			)
			(polygon
				(pts
					(xy 135.5852 -100.203) (xy 135.7376 -100.203) (xy 135.7376 -100.8126) (xy 135.5852 -100.8126)
				)
			)
		)
	)
	(footprint ""
		(layer "F.Cu")
		(at 105.8418 -72.517 180)
		(property "Reference" "C240"
			(at -0.3302 -4.09067 0)
			(unlocked yes)
			(layer "F.SilkS")
			(effects
				(font
					(size 0.7874 0.5842)
					(thickness 0.1524)
				)
			)
		)
		(property "Value" "VAL*"
			(at 0.0762 3.134106 180)
			(unlocked yes)
			(layer "F.Fab")
			(hide yes)
			(effects
				(font
					(size 0.7874 0.5842)
					(thickness 0.1524)
				)
			)
		)
		(property "Device Type" "CAPACITOR-G107-0F226-CM,22UF,2A"
			(at 0.0508 2.194306 180)
			(unlocked yes)
			(layer "F.Fab")
			(hide yes)
			(effects
				(font
					(size 0.7874 0.5842)
					(thickness 0.1524)
				)
			)
		)
		(property "User Part Number" "PARTNUM*"
			(at 0.1016 5.013706 180)
			(unlocked yes)
			(layer "Cmts.User")
			(hide yes)
			(effects
				(font
					(size 0.7874 0.5842)
					(thickness 0.1524)
				)
			)
		)
		(property "Tolerance" "TOL*"
			(at 0.0762 4.048506 180)
			(unlocked yes)
			(layer "Cmts.User")
			(hide yes)
			(effects
				(font
					(size 0.7874 0.5842)
					(thickness 0.1524)
				)
			)
		)
		(duplicate_pad_numbers_are_jumpers no)
		(fp_line
			(start 1.5748 0.9398)
			(end 1.5748 -0.9398)
			(stroke
				(width 0.1)
				(type default)
			)
			(layer "F.SilkS")
		)
		(fp_line
			(start 1.5748 -0.9398)
			(end -1.5748 -0.9398)
			(stroke
				(width 0.1)
				(type default)
			)
			(layer "F.SilkS")
		)
		(fp_line
			(start -1.5748 0.9398)
			(end 1.5748 0.9398)
			(stroke
				(width 0.1)
				(type default)
			)
			(layer "F.SilkS")
		)
		(fp_line
			(start -1.5748 -0.9398)
			(end -1.5748 0.9398)
			(stroke
				(width 0.1)
				(type default)
			)
			(layer "F.SilkS")
		)
		(fp_rect
			(start -1.5748 0.9398)
			(end 1.5748 -0.9398)
			(stroke
				(width 0)
				(type default)
			)
			(fill no)
			(layer "F.CrtYd")
		)
		(fp_line
			(start 1.016 0.635)
			(end 1.016 -0.635)
			(stroke
				(width 0.1)
				(type default)
			)
			(layer "F.Fab")
		)
		(fp_line
			(start 1.016 -0.635)
			(end -1.016 -0.635)
			(stroke
				(width 0.1)
				(type default)
			)
			(layer "F.Fab")
		)
		(fp_line
			(start -1.016 0.635)
			(end 1.016 0.635)
			(stroke
				(width 0.1)
				(type default)
			)
			(layer "F.Fab")
		)
		(fp_line
			(start -1.016 -0.635)
			(end -1.016 0.635)
			(stroke
				(width 0.1)
				(type default)
			)
			(layer "F.Fab")
		)
		(pad "1" smd rect
			(at -0.8382 0 180)
			(size 0.9652 1.3716)
			(layers "F.Cu" "F.Mask" "F.Paste")
			(net "XP3R3V_FPGA")
		)
		(pad "2" smd rect
			(at 0.8382 0 180)
			(size 0.9652 1.3716)
			(layers "F.Cu" "F.Mask" "F.Paste")
			(net "SG")
		)
		(zone
			(layer "F.Cu")
			(hatch none 0.5)
			(connect_pads
				(clearance 0)
			)
			(min_thickness 0.25)
			(keepout
				(tracks allowed)
				(vias not_allowed)
				(pads allowed)
				(copperpour not_allowed)
				(footprints allowed)
			)
			(placement
				(enabled no)
				(sheetname "")
			)
			(fill
				(thermal_gap 0.5)
				(thermal_bridge_width 0.5)
				(island_removal_mode 0)
			)
			(polygon
				(pts
					(xy 106.0704 -73.152) (xy 105.6132 -73.152) (xy 105.6132 -71.882) (xy 106.0704 -71.882)
				)
			)
		)
	)
)
